FILE_TYPE=LIBRARY_PARTS;
primitive 'CONN4_HFK1040L0P1L7H';
  pin
    '4':
      PIN_NUMBER='(4)';
      BIDIRECTIONAL='TRUE';
      INPUT_LOAD='(-0.01,0.01)';
      OUTPUT_LOAD='(1.0,-1.0)';
    '3':
      PIN_NUMBER='(3)';
      BIDIRECTIONAL='TRUE';
      INPUT_LOAD='(-0.01,0.01)';
      OUTPUT_LOAD='(1.0,-1.0)';
    '2':
      PIN_NUMBER='(2)';
      BIDIRECTIONAL='TRUE';
      INPUT_LOAD='(-0.01,0.01)';
      OUTPUT_LOAD='(1.0,-1.0)';
    '1':
      PIN_NUMBER='(1)';
      BIDIRECTIONAL='TRUE';
      INPUT_LOAD='(-0.01,0.01)';
      OUTPUT_LOAD='(1.0,-1.0)';
  end_pin;
  body
    PART_NAME='CONN4_HFK1040L0P1L7H';
    BODY_NAME='CONN4_HFK1040L0P1L7H';
    PHYS_DES_PREFIX='J';
    CLASS='IO';
    NC_PINS='(H1)';
  end_body;
end_primitive;

END.
